5
5
4
4
3
3
2
2
1
1
D D
C C
B B
A A
Power Distribution Backplane 
Version: 2013/12/26 
PCB: PDB PCB 
LAYER: 8 
Title 
Size Document Number Rev
Date: Sheet 
of 
N/A 1A
Power Distribution Backplane V2 
Microsoft Corporation 
C
1 11Tuesday, February 10, 2015 
Title 
Size Document Number Rev
Date: Sheet 
of 
N/A 1A
Power Distribution Backplane V2 
Microsoft Corporation 
C
1 11Tuesday, February 10, 2015 
Title 
Size Document Number Rev
Date: Sheet 
of 
N/A 1A
Power Distribution Backplane V2 
Microsoft Corporation 
C
1 11Tuesday, February 10, 2015 



5
5
4
4
3
3
2
2
1
1
D D
C C
B B
A A
Title 
Size Document Number Rev
Date: Sheet 
of 
N/A 1A
Power Distribution Backplane V2 
Microsoft Corporation 
C
2 11Monday, November 24, 2014 
Title 
Size Document Number Rev
Date: Sheet 
of 
N/A 1A
Power Distribution Backplane V2 
Microsoft Corporation 
C
2 11Monday, November 24, 2014 
Title 
Size Document Number Rev
Date: Sheet 
of 
N/A 1A
Power Distribution Backplane V2 
Microsoft Corporation 
C
2 11Monday, November 24, 2014 



5
5
4
4
3
3
2
2
1
1
D D
C C
B B
A A
Title 
Size Document Number Rev
Date: Sheet 
of 
N/A 1A
Power Distribution Backplane V2 
Microsoft Corporation 
C
3 11Monday, November 24, 2014 
Title 
Size Document Number Rev
Date: Sheet 
of 
N/A 1A
Power Distribution Backplane V2 
Microsoft Corporation 
C
3 11Monday, November 24, 2014 
Title 
Size Document Number Rev
Date: Sheet 
of 
N/A 1A
Power Distribution Backplane V2 
Microsoft Corporation 
C
3 11Monday, November 24, 2014 



5
5
4
4
3
3
2
2
1
1
D D
C C
B B
A A
PSU_ALERT_N B1_PSU_ALERT_N 
B2_PSU_ALERT_N 
B3_PSU_ALERT_N 
B4_PSU_ALERT_N 
B5_PSU_ALERT_N 
B6_PSU_ALERT_N 
PSU_ALERT_N B7_PSU_ALERT_N 
B8_PSU_ALERT_N 
B9_PSU_ALERT_N 
B10_PSU_ALERT_N 
B11_PSU_ALERT_N 
B12_PSU_ALERT_N 
PSU_ALERT_N B13_PSU_ALERT_N 
B14_PSU_ALERT_N 
B15_PSU_ALERT_N 
B16_PSU_ALERT_N 
B17_PSU_ALERT_N 
B18_PSU_ALERT_N 
PSU_ALERT_N B19_PSU_ALERT_N 
B20_PSU_ALERT_N 
B21_PSU_ALERT_N 
B22_PSU_ALERT_N 
B23_PSU_ALERT_N 
B24_PSU_ALERT_N 
PSU_ALERT_N 5,8 B1_PSU_ALERT_N 6
B2_PSU_ALERT_N 6
B3_PSU_ALERT_N 6
B4_PSU_ALERT_N 6
B5_PSU_ALERT_N 6
B6_PSU_ALERT_N 6
B7_PSU_ALERT_N 6
B8_PSU_ALERT_N 6
B9_PSU_ALERT_N 6
B10_PSU_ALERT_N 6
B11_PSU_ALERT_N 6
B12_PSU_ALERT_N 6
B13_PSU_ALERT_N 7
B14_PSU_ALERT_N 7
B15_PSU_ALERT_N 7
B16_PSU_ALERT_N 7
B17_PSU_ALERT_N 7
B18_PSU_ALERT_N 7
B19_PSU_ALERT_N 7
B20_PSU_ALERT_N 7
B21_PSU_ALERT_N 7
B22_PSU_ALERT_N 7
B23_PSU_ALERT_N 7
B24_PSU_ALERT_N 7
P3V3_BUF 
P3V3_BUF 
P3V3_BUF 
P3V3_BUF 
Title 
Size Document Number Rev
Date: Sheet 
of 
N/A 1A
Power Distribution Backplane V2 
Microsoft Corporation 
C
4 11Monday, November 24, 2014 
Title 
Size Document Number Rev
Date: Sheet 
of 
N/A 1A
Power Distribution Backplane V2 
Microsoft Corporation 
C
4 11Monday, November 24, 2014 
Title 
Size Document Number Rev
Date: Sheet 
of 
N/A 1A
Power Distribution Backplane V2 
Microsoft Corporation 
C
4 11Monday, November 24, 2014 
U5F 
74LVC07 
13 12 
U4E 
74LVC07 
11 10 
R162 
4.7K NI 
R0402 
5% 
C93 
0.1UF 
C0402 
10% 
25V 
U4F 
74LVC07 
13 12 
C95 
0.1UF 
C0402 
10% 
25V 
U5A 
74LVC07 
1 2
14 7
U7A 
74LVC07 
1 2
14 7
C94 
0.1UF 
C0402 
10% 
25V 
U4A 
74LVC07 
1 2
14 7
U5B 
74LVC07 
3 4
U7B 
74LVC07 
3 4
U6A 
74LVC07 
1 2
14 7
U7C 
74LVC07 
5 6
U5C 
74LVC07 
5 6
U4B 
74LVC07 
3 4
U6B 
74LVC07 
3 4
U7D 
74LVC07 
9 8
U6C 
74LVC07 
5 6
U7E 
74LVC07 
11 10 
U5D 
74LVC07 
9 8
U4C 
74LVC07 
5 6
U6D 
74LVC07 
9 8
U7F 
74LVC07 
13 12 
U5E 
74LVC07 
11 10 
U6E 
74LVC07 
11 10 
U4D 
74LVC07 
9 8
C96 
0.1UF 
C0402 
10% 
25V 
U6F 
74LVC07 
13 12 



5
5
4
4
3
3
2
2
1
1
D D
C C
B B
A A
PSU1 
PSU CONNECTOR 
Internal PU 3.3V: 
SDA:6.7K 
SCL:6.7K 
ALERT:100K 
RESET:100K 
PS_KILL:10K 
PRSNT:100 
POK:1K 
VIN_GOOD:1K 
PSU2 
Internal PU 3.3V: 
SDA:6.7K 
SCL:6.7K 
ALERT:100K 
RESET:100K 
PS_KILL:10K 
PRSNT:100 
POK:1K 
VIN_GOOD:1K 
PSU3 
PSU4 
Internal PU 3.3V: 
SDA:6.7K 
SCL:6.7K 
ALERT:100K 
RESET:100K 
PS_KILL:10K 
PRSNT:100 
POK:1K 
VIN_GOOD:1K 
Internal PU 3.3V: 
SDA:6.7K 
SCL:6.7K 
ALERT:100K 
RESET:100K 
PS_KILL:10K 
PRSNT:100 
POK:1K 
VIN_GOOD:1K 
PSU6 
Internal PU 3.3V: 
SDA:6.7K 
SCL:6.7K 
ALERT:100K 
RESET:100K 
PS_KILL:10K 
PRSNT:100 
POK:1K 
VIN_GOOD:1K 
PSU5 
Internal PU 3.3V: 
SDA:6.7K 
SCL:6.7K 
ALERT:100K 
RESET:100K 
PS_KILL:10K 
PRSNT:100 
POK:1K 
VIN_GOOD:1K 
3.276V 
PSU1_REMOTE_N 
PSU1_CSAHRE 
PSU1_REMOTE_P 
PSU1_AD0 
PSU1_RETURN 
PSU1_REMOTE_N 
PSU1_REMOTE_P 
PSU1_RETURN 
PSU2_REMOTE_P 
PSU2_REMOTE_N 
PSU2_RETURN 
PSU3_REMOTE_P 
PSU3_REMOTE_N 
PSU3_RETURN 
PSU4_REMOTE_P 
PSU4_REMOTE_N 
PSU4_RETURN 
PSU6_REMOTE_P 
PSU6_REMOTE_N 
PSU6_RETURN 
PSU1_AD0 
PSU4_AD0 
PSU3_AD0 
PSU2_REMOTE_N 
PSU2_CSAHRE 
PSU_ALERT_N 
PSU2_REMOTE_P 
PSU2_AD0 
PSU2_RETURN 
I2C_PSU1_SCL 
I2C_PSU1_SDA 
PSU3_REMOTE_N 
PSU3_CSAHRE 
PSU_ALERT_N 
PSU4_REMOTE_N 
PSU4_CSAHRE 
PSU_ALERT_N 
PSU3_REMOTE_P 
PSU3_AD0 
PSU3_RETURN 
PSU4_REMOTE_P 
PSU4_AD0 
PSU4_RETURN 
I2C_PSU2_SCL 
I2C_PSU2_SDA 
PSU6_REMOTE_P 
PSU6_AD0 
PSU6_RETURN 
I2C_PSU3_SCL 
I2C_PSU3_SDA 
PSU6_REMOTE_N 
PSU6_CSAHRE 
PSU_ALERT_N 
PSU5_REMOTE_P 
PSU5_REMOTE_N 
PSU5_RETURN 
PSU5_AD0 
PSU5_REMOTE_P 
PSU5_AD0 
PSU5_RETURN 
PSU5_REMOTE_N 
PSU5_CSAHRE 
PSU_ALERT_N 
PSU2_AD0 
PSU6_AD0 
PSU1_RESET 
PSU1_PS_KILL 
PSU1_PS_KILL 
PSU1_RESET PSU2_RESET 
PSU2_PS_KILL 
PSU2_RESET 
PSU2_PS_KILL 
PSU3_RESET 
PSU3_PS_KILL 
PSU3_PS_KILL 
PSU3_RESET 
PSU4_RESET 
PSU4_PS_KILL 
PSU4_RESET 
PSU4_PS_KILL 
PSU5_PS_KILL 
PSU5_RESET 
PSU5_RESET 
PSU5_PS_KILL 
PSU6_PS_KILL 
PSU6_RESET 
PSU6_RESET 
PSU6_PS_KILL 
PSU1_PS_KILL 
PSU1_RESET 
PSU2_PS_KILL 
PSU2_RESET 
PSU3_PS_KILL 
PSU3_RESET 
PSU4_PS_KILL 
PSU4_RESET 
PSU5_PS_KILL 
PSU5_RESET 
PSU6_PS_KILL 
PSU6_RESET 
PSU1_REMOTE_P 
PSU1_REMOTE_N 
PSU1_REMOTE_R_P 
PSU1_REMOTE_R_N 
PSU2_REMOTE_R_N 
PSU2_REMOTE_P 
PSU2_REMOTE_N 
PSU2_REMOTE_R_P 
PSU3_REMOTE_R_N 
PSU3_REMOTE_P 
PSU3_REMOTE_N 
PSU3_REMOTE_R_P 
PSU6_REMOTE_R_N 
PSU6_REMOTE_P 
PSU6_REMOTE_N 
PSU6_REMOTE_R_P 
PSU5_REMOTE_R_N 
PSU5_REMOTE_P 
PSU5_REMOTE_N 
PSU5_REMOTE_R_P 
PSU4_REMOTE_R_N 
PSU4_REMOTE_P 
PSU4_REMOTE_N 
PSU4_REMOTE_R_P 
PSU1_REMOTE_P PSU1_REMOTE_R2_P 
PSU1_REMOTE_R2_N PSU1_REMOTE_N 
PSU2_REMOTE_P PSU2_REMOTE_R2_P 
PSU2_REMOTE_R2_N PSU2_REMOTE_N 
PSU3_REMOTE_P PSU3_REMOTE_R2_P 
PSU3_REMOTE_R2_N PSU3_REMOTE_N 
PSU4_REMOTE_P PSU4_REMOTE_R2_P 
PSU4_REMOTE_R2_N PSU4_REMOTE_N 
PSU5_REMOTE_P PSU5_REMOTE_R2_P 
PSU5_REMOTE_R2_N PSU5_REMOTE_N 
PSU6_REMOTE_P PSU6_REMOTE_R2_P 
PSU6_REMOTE_R2_N PSU6_REMOTE_N 
PSU1_CSAHRE PSU_CSAHRE 
PSU2_CSAHRE 
PSU3_CSAHRE 
PSU4_CSAHRE 
PSU5_CSAHRE 
PSU6_CSAHRE 
PHLOSS PHLOSS PHLOSS 
PHLOSS PHLOSS PHLOSS 
PHLOSS 
PSU1_PS_ON_N 8
I2C_PSU1_SCL 8
I2C_PSU1_SDA 8PSU_ALERT_N 4,8 
PSU2_PS_ON_N 8 PSU3_PS_ON_N 8
PSU4_PS_ON_N 8
I2C_PSU2_SCL 8
I2C_PSU2_SDA 8
PSU6_PS_ON_N 8
I2C_PSU3_SCL 8
I2C_PSU3_SDA 8
PSU5_PS_ON_N 8
PSU1_AC_OK 8 PSU2_AC_OK 8 PSU3_AC_OK 8
PSU6_AC_OK 8PSU5_AC_OK 8PSU4_AC_OK 8
PSU4_DC_OK 8 PSU5_DC_OK 8 PSU6_DC_OK 8
PSU1_DC_OK 8 PSU2_DC_OK 8 PSU3_DC_OK 8
P12V P12V 
P12V_STBY 
P12V 
P12V 
P12V_STBY 
P12V 
P12V 
P12V 
P12V 
P12V_STBY 
P12V 
P12V_STBY 
P12V 
P12V 
P12V 
P12V 
P12V_STBY 
P12V 
P12V 
P12V_STBY 
P12V 
P12V_STBY 
P12V 
P12V 
P12V_STBY 
P12V_STBY 
P12V_STBY P12V_STBY
P12V_STBY 
P12V_STBY 
P12V_STBY 
P12V_STBY 
P12V_STBY 
P12V_STBY
P12V_STBY
P12V_STBY 
P12V_STBY 
P12V_STBY 
P12V_STBY 
P12V_STBY
P12V_STBY 
P12V 
P12V 
P12V 
P12V 
P12V 
P12V 
P12V 
Title 
Size Document Number Rev
Date: Sheet 
of 
N/A 1A
Power Distribution Backplane V2 
Microsoft Corporation 
C
5 11Monday, November 24, 2014 
Title 
Size Document Number Rev
Date: Sheet 
of 
N/A 1A
Power Distribution Backplane V2 
Microsoft Corporation 
C
5 11Monday, November 24, 2014 
Title 
Size Document Number Rev
Date: Sheet 
of 
N/A 1A
Power Distribution Backplane V2 
Microsoft Corporation 
C
5 11Monday, November 24, 2014 
R14 0
R0402 1% 
NI 
R88 0
R0402 1% 
R96 0
R0402 1% 
J1 
10046971-001LF 
REMOTE SENSE- 26 
VIN_GOOD 27 
CSHARE 28 
-PS_ON 29 
PS_KILL 30 
RESET 31 
ALERT 32 
TACH 25 REMOTE SENSE+ 40 
12V_SB 39 
PS_A0 38 
POK 37 
RETURN 36 
SCL 35 
-PS_PRESENT 34 
SDA 33 
+12V_1 1
+12V_2 2
+12V_3 3
+12V_4 4
+12V_5 5
+12V_6 6
+12V_7 7
+12V_8 8
+12V_9 9
+12V_10 10 
+12V_11 11 
+12V_12 12 
+12V_24 64 
+12V_23 63 
+12V_22 62 
+12V_21 61 
+12V_20 60 
+12V_19 59 
+12V_18 58 
+12V_17 57 
+12V_16 56 
+12V_15 55 
+12V_14 54 
+12V_13 53 
RTN1 13 
RTN2 14 
RTN3 15 
RTN4 16 
RTN5 17 
RTN6 18 
RTN7 19 
RTN8 20 
RTN9 21 
RTN10 22 
RTN11 23 
RTN12 24 
RTN24 52 
RTN23 51 
RTN22 50 
RTN21 49 
RTN20 48 
RTN19 47 
RTN18 46 
RTN17 45 
RTN16 44 
RTN15 43 
RTN14 42 
RTN13 41 
R1 0
R0402 1% 
NI 
R12 100 
R25 100 
R138 0
R0402 1% 
R125 0
R0402 1% 
NI 
R11 100 
R133 0
R0402 1% 
NI 
R126 0
R0402 1% 
NI 
R131 0
R0402 1% 
NI 
R120 0
R0402 1% 
NI 
R7 0
R0402 1% 
NI 
R20 0
R0402 1% 
NI 
R92 0
R0402 1% 
R79 8.2K 
5% R0402 
NI 
R66 22.1K 
1% R0402 
NI 
R17 0
R0402 1% 
NI 
R18 22.1K 
1% R0402 
R83 8.2K 
5% R0402 
NI 
R103 0
R0402 1% 
J3 
10046971-001LF 
REMOTE SENSE- 26 
VIN_GOOD 27 
CSHARE 28 
-PS_ON 29 
PS_KILL 30 
RESET 31 
ALERT 32 
TACH 25 REMOTE SENSE+ 40 
12V_SB 39 
PS_A0 38 
POK 37 
RETURN 36 
SCL 35 
-PS_PRESENT 34 
SDA 33 
+12V_1 1
+12V_2 2
+12V_3 3
+12V_4 4
+12V_5 5
+12V_6 6
+12V_7 7
+12V_8 8
+12V_9 9
+12V_10 10 
+12V_11 11 
+12V_12 12 
+12V_24 64 
+12V_23 63 
+12V_22 62 
+12V_21 61 
+12V_20 60 
+12V_19 59 
+12V_18 58 
+12V_17 57 
+12V_16 56 
+12V_15 55 
+12V_14 54 
+12V_13 53 
RTN1 13 
RTN2 14 
RTN3 15 
RTN4 16 
RTN5 17 
RTN6 18 
RTN7 19 
RTN8 20 
RTN9 21 
RTN10 22 
RTN11 23 
RTN12 24 
RTN24 52 
RTN23 51 
RTN22 50 
RTN21 49 
RTN20 48 
RTN19 47 
RTN18 46 
RTN17 45 
RTN16 44 
RTN15 43 
RTN14 42 
RTN13 41 
R89 0
R0402 1% 
R60 100 
R158 
22.1K 
1% 
R0402 
R135 0
R0402 1% 
R23 8.2K 
5% R0402 
R78 22.1K 
1% R0402 
NI 
R121 0
R0402 1% 
NI 
R61 100 
R67 8.2K 
5% R0402 
NI 
R19 0
R0402 1% 
NI 
R8 8.2K 
5% R0402 R13 100 
R86 0
R0402 1% 
R127 0
R0402 1% 
NI 
R97 0
R0402 1% 
R104 0
R0402 1% 
R73 8.2K 
5% R0402 
NI 
R77 8.2K 
5% R0402 
NI 
R87 0
R0402 1% 
R2 0
R0402 1% 
NI 
R26 100 
R122 0
R0402 1% 
NI 
R4 22.1K 
1% R0402 
R106 0
R0402 1% 
R27 100 
R58 100 
R22 0
R0402 1% 
NI 
R93 0
R0402 1% 
R84 22.1K 
1% R0402 
NI 
R159 
8.2K 
1% 
R0402 
R72 22.1K 
1% R0402 
NI 
C92 
2.2UF 
10V 
C0603 
NI 
R76 22.1K 
1% R0402 
NI 
R10 100 
R137 0
R0402 1% 
R5 0
R0402 1% 
NI 
R123 0
R0402 1% 
NI 
R134 0
R0402 1% 
R59 100 
R44 100K 
CHIP 
NI 
R105 0
R0402 1% 
R114 0
R0402 1% 
NI 
R85 8.2K 
5% R0402 
NI 
R81 8.2K 
5% R0402 
NI 
R40 100K 
R98 0
R0402 1% 
R68 22.1K 
1% R0402 
NI 
R107 0
R0402 1% 
R43 100 
R45 100 
J2 
10046971-001LF 
REMOTE SENSE- 26 
VIN_GOOD 27 
CSHARE 28 
-PS_ON 29 
PS_KILL 30 
RESET 31 
ALERT 32 
TACH 25 REMOTE SENSE+ 40 
12V_SB 39 
PS_A0 38 
POK 37 
RETURN 36 
SCL 35 
-PS_PRESENT 34 
SDA 33 
+12V_1 1
+12V_2 2
+12V_3 3
+12V_4 4
+12V_5 5
+12V_6 6
+12V_7 7
+12V_8 8
+12V_9 9
+12V_10 10 
+12V_11 11 
+12V_12 12 
+12V_24 64 
+12V_23 63 
+12V_22 62 
+12V_21 61 
+12V_20 60 
+12V_19 59 
+12V_18 58 
+12V_17 57 
+12V_16 56 
+12V_15 55 
+12V_14 54 
+12V_13 53 
RTN1 13 
RTN2 14 
RTN3 15 
RTN4 16 
RTN5 17 
RTN6 18 
RTN7 19 
RTN8 20 
RTN9 21 
RTN10 22 
RTN11 23 
RTN12 24 
RTN24 52 
RTN23 51 
RTN22 50 
RTN21 49 
RTN20 48 
RTN19 47 
RTN18 46 
RTN17 45 
RTN16 44 
RTN15 43 
RTN14 42 
RTN13 41 
R80 22.1K 
1% R0402 
NI 
R69 8.2K 
5% R0402 
NI R118 0
R0402 1% 
NI 
R62 22.1K 
1% R0402 
NI 
R115 0
R0402 1% 
NI 
R6 0
R0402 1% 
NI 
R64 22.1K 
1% R0402 
NI 
R46 100 
R99 0
R0402 1% 
R108 0
R0402 1% 
J4 
10046971-001LF 
REMOTE SENSE- 26 
VIN_GOOD 27 
CSHARE 28 
-PS_ON 29 
PS_KILL 30 
RESET 31 
ALERT 32 
TACH 25 REMOTE SENSE+ 40 
12V_SB 39 
PS_A0 38 
POK 37 
RETURN 36 
SCL 35 
-PS_PRESENT 34 
SDA 33 
+12V_1 1
+12V_2 2
+12V_3 3
+12V_4 4
+12V_5 5
+12V_6 6
+12V_7 7
+12V_8 8
+12V_9 9
+12V_10 10 
+12V_11 11 
+12V_12 12 
+12V_24 64 
+12V_23 63 
+12V_22 62 
+12V_21 61 
+12V_20 60 
+12V_19 59 
+12V_18 58 
+12V_17 57 
+12V_16 56 
+12V_15 55 
+12V_14 54 
+12V_13 53 
RTN1 13 
RTN2 14 
RTN3 15 
RTN4 16 
RTN5 17 
RTN6 18 
RTN7 19 
RTN8 20 
RTN9 21 
RTN10 22 
RTN11 23 
RTN12 24 
RTN24 52 
RTN23 51 
RTN22 50 
RTN21 49 
RTN20 48 
RTN19 47 
RTN18 46 
RTN17 45 
RTN16 44 
RTN15 43 
RTN14 42 
RTN13 41 
R16 22.1K 
1% R0402 
R56 100 
R139 0
R0402 1% 
R128 0
R0402 1% 
NI 
R24 100 
R63 8.2K 
5% R0402 
NI 
R116 0
R0402 1% 
NI 
R65 8.2K 
5% R0402 
NI 
R48 100 
R100 0
R0402 1% 
R110 0
R0402 1% 
NI 
R94 0
R0402 1% 
R119 0
R0402 1% 
NI 
R3 0
R0402 1% 
NI 
R112 0
R0402 1% 
NI 
R21 8.2K 
5% R0402 
R136 0
R0402 1% 
R129 0
R0402 1% 
NI 
R47 100 
R15 0
R0402 1% 
NI 
R55 100 
R109 0
R0402 1% 
J5 
10046971-001LF 
REMOTE SENSE- 26 
VIN_GOOD 27 
CSHARE 28 
-PS_ON 29 
PS_KILL 30 
RESET 31 
ALERT 32 
TACH 25 REMOTE SENSE+ 40 
12V_SB 39 
PS_A0 38 
POK 37 
RETURN 36 
SCL 35 
-PS_PRESENT 34 
SDA 33 
+12V_1 1
+12V_2 2
+12V_3 3
+12V_4 4
+12V_5 5
+12V_6 6
+12V_7 7
+12V_8 8
+12V_9 9
+12V_10 10 
+12V_11 11 
+12V_12 12 
+12V_24 64 
+12V_23 63 
+12V_22 62 
+12V_21 61 
+12V_20 60 
+12V_19 59 
+12V_18 58 
+12V_17 57 
+12V_16 56 
+12V_15 55 
+12V_14 54 
+12V_13 53 
RTN1 13 
RTN2 14 
RTN3 15 
RTN4 16 
RTN5 17 
RTN6 18 
RTN7 19 
RTN8 20 
RTN9 21 
RTN10 22 
RTN11 23 
RTN12 24 
RTN24 52 
RTN23 51 
RTN22 50 
RTN21 49 
RTN20 48 
RTN19 47 
RTN18 46 
RTN17 45 
RTN16 44 
RTN15 43 
RTN14 42 
RTN13 41 
R111 0
R0402 1% 
NI 
R95 0
R0402 1% 
R117 0
R0402 1% 
NI 
R57 100 
R160 
0
1% 
R0402 
R90 0
R0402 1% 
R75 8.2K 
5% R0402 
NI 
R9 100 
R71 8.2K 
5% R0402 
NI 
R130 0
R0402 1% 
NI 
R113 0
R0402 1% 
NI 
R124 0
R0402 1% 
NI 
R42 100K NI 
J6 
10046971-001LF 
REMOTE SENSE- 26 
VIN_GOOD 27 
CSHARE 28 
-PS_ON 29 
PS_KILL 30 
RESET 31 
ALERT 32 
TACH 25 REMOTE SENSE+ 40 
12V_SB 39 
PS_A0 38 
POK 37 
RETURN 36 
SCL 35 
-PS_PRESENT 34 
SDA 33 
+12V_1 1
+12V_2 2
+12V_3 3
+12V_4 4
+12V_5 5
+12V_6 6
+12V_7 7
+12V_8 8
+12V_9 9
+12V_10 10 
+12V_11 11 
+12V_12 12 
+12V_24 64 
+12V_23 63 
+12V_22 62 
+12V_21 61 
+12V_20 60 
+12V_19 59 
+12V_18 58 
+12V_17 57 
+12V_16 56 
+12V_15 55 
+12V_14 54 
+12V_13 53 
RTN1 13 
RTN2 14 
RTN3 15 
RTN4 16 
RTN5 17 
RTN6 18 
RTN7 19 
RTN8 20 
RTN9 21 
RTN10 22 
RTN11 23 
RTN12 24 
RTN24 52 
RTN23 51 
RTN22 50 
RTN21 49 
RTN20 48 
RTN19 47 
RTN18 46 
RTN17 45 
RTN16 44 
RTN15 43 
RTN14 42 
RTN13 41 
R161 0
1% R0402 
R132 0
R0402 1% 
NI 
R102 0
R0402 1% 
R74 22.1K 
1% R0402 
NI 
R91 0
R0402 1% 
U3 
TL431BCDR2G 
NI 
C1
NC1 4 NC2 5A3 6A4 7REF 8
A1 2
A2 3
R101 0
R0402 1% 
R82 22.1K 
1% R0402 
NI 
R70 22.1K 
1% R0402 
NI 



5
5
4
4
3
3
2
2
1
1
D D
C C
B B
A A
TRAY 1 TRAY 2 TRAY 3 
TRAY 4 TRAY 5 TRAY 6 
FOR TRAY1 FOR TRAY2 FOR TRAY3 FOR TRAY4 
FOR TRAY5 FOR TRAY6 
B3_PSU_ALERT_N 4
T2_BLAD3_TXD 8
T2_BLAD3_EN 8
T2_BLAD4_TXD 8
B4_PSU_ALERT_N 4
T2_BLAD1_TXD 8
T2_BLAD1_EN 8
T2_BLAD2_TXD 8
T2_BLAD2_RXD 8
T2_BLAD1_RXD 8 T2_BLAD3_RXD 8
T2_BLAD4_RXD 8
B5_PSU_ALERT_N 4
T3_BLAD3_TXD 8
T3_BLAD3_EN 8
T3_BLAD4_TXD 8
T3_BLAD3_RXD 8
B6_PSU_ALERT_N 4
T3_BLAD1_TXD 8
T3_BLAD1_RXD 8
T3_BLAD4_RXD 8
T3_BLAD1_EN 8
T3_BLAD2_TXD 8
T3_BLAD2_RXD 8
B7_PSU_ALERT_N 4
T4_BLAD3_TXD 8
T4_BLAD3_EN 8
T4_BLAD4_TXD 8
T4_BLAD3_RXD 8
B8_PSU_ALERT_N 4
T4_BLAD1_TXD 8
T4_BLAD1_RXD 8
T4_BLAD4_RXD 8
T4_BLAD1_EN 8
T4_BLAD2_TXD 8
T4_BLAD2_RXD 8
B11_PSU_ALERT_N 4
T6_BLAD3_TXD 8
T6_BLAD3_EN 8
T6_BLAD4_TXD 8
T6_BLAD3_RXD 8
B12_PSU_ALERT_N 4
T6_BLAD1_TXD 8
T6_BLAD1_RXD 8
T6_BLAD4_RXD 8
T6_BLAD1_EN 8
T6_BLAD2_TXD 8
T6_BLAD2_RXD 8
B1_PSU_ALERT_N 4
T1_BLAD3_TXD 8
T1_BLAD3_EN 8
T1_BLAD4_TXD 8
T1_BLAD3_RXD 8
B2_PSU_ALERT_N 4
T1_BLAD1_TXD 8
T1_BLAD1_RXD 8
T1_BLAD4_RXD 8
T1_BLAD1_EN 8
T1_BLAD2_TXD 8
T1_BLAD2_RXD 8
B9_PSU_ALERT_N 4
T5_BLAD3_TXD 8
T5_BLAD3_EN 8
T5_BLAD4_TXD 8
T5_BLAD3_RXD 8
B10_PSU_ALERT_N 4
T5_BLAD1_TXD 8
T5_BLAD1_RXD 8
T5_BLAD4_RXD 8
T5_BLAD1_EN 8
T5_BLAD2_TXD 8
T5_BLAD2_RXD 8
P12V P12V P12V 
P12V 
P12V P12V P12V 
P12V P12V P12V P12V 
P12V P12V 
P12V P12V P12V 
P12V P12V P12V 
Title 
Size Document Number Rev
Date: Sheet 
of 
N/A 1A
Power Distribution Backplane V2 
Microsoft Corporation 
C
6 11Monday, November 24, 2014 
Title 
Size Document Number Rev
Date: Sheet 
of 
N/A 1A
Power Distribution Backplane V2 
Microsoft Corporation 
C
6 11Monday, November 24, 2014 
Title 
Size Document Number Rev
Date: Sheet 
of 
N/A 1A
Power Distribution Backplane V2 
Microsoft Corporation 
C
6 11Monday, November 24, 2014 
C18 
0.1UF 
25V 
C0402 
+ CE11 
470UF 
16V 
1 2
C35 
100PF 
50V 
C0402 
Signal 
SEG1 
SEG2 
SEG3 
SEG4 SEG5 
SEG6 
SEG7 
SEG8 
PRESS-FIT 
ORIENTATION KEY 
J12 
CONN44_10117936003LF 
S3 S3 
S4 S4 
S5 S5 
S6 S6 
S12 S12 
S11 S11 
S10 S10 
S9 S9 
S8 S8 
S7 S7 
P16 P16 P15 P15 P14 P14 P13 P13 
P1 P1 
P2 P2 
P3 P3 
P12 P12 P11 P11 P10 P10 P9 P9 
P5 P5 
P6 P6 
P7 P7 
P8 P8 
S2 S2 S1 S1 
P4 P4 
P17 P17 P18 P18 P19 P19 P20 P20 
P21 P21 P22 P22 P23 P23 P24 P24 
P25 P25 P26 P26 P27 P27 P28 P28 
P29 P29 P30 P30 P31 P31 P32 P32 
C16 
0.1UF 
25V 
C0402 
C34 
0.1UF 
25V 
C0402 
C39 
0.1UF 
25V 
C0402 
+ CE1 
470UF 
16V 
1 2
C30 
0.1UF 
25V 
C0402 
C2 
0.1UF 
25V 
C0402 
C10 
0.1UF 
25V 
C0402 
C33 
0.1UF 
25V 
C0402 
Signal 
SEG1 
SEG2 
SEG3 
SEG4 SEG5 
SEG6 
SEG7 
SEG8 
PRESS-FIT 
ORIENTATION KEY 
J9 
CONN44_10117936003LF 
S3 S3 
S4 S4 
S5 S5 
S6 S6 
S12 S12 
S11 S11 
S10 S10 
S9 S9 
S8 S8 
S7 S7 
P16 P16 P15 P15 P14 P14 P13 P13 
P1 P1 
P2 P2 
P3 P3 
P12 P12 P11 P11 P10 P10 P9 P9 
P5 P5 
P6 P6 
P7 P7 
P8 P8 
S2 S2 S1 S1 
P4 P4 
P17 P17 P18 P18 P19 P19 P20 P20 
P21 P21 P22 P22 P23 P23 P24 P24 
P25 P25 P26 P26 P27 P27 P28 P28 
P29 P29 P30 P30 P31 P31 P32 P32 
C19 
0.1UF 
25V 
C0402 
C21 
100PF 
50V 
C0402 
+ CE5 
470UF 
16V 
1 2
C9 
0.1UF 
25V 
C0402 
C14 
100PF 
50V 
C0402 
C8 
1UF 
25V 
C0603 
C23 
0.1UF 
25V 
C0402 
C6 
0.1UF 
25V 
C0402 
C31 
0.1UF 
25V 
C0402 
Signal 
SEG1 
SEG2 
SEG3 
SEG4 SEG5 
SEG6 
SEG7 
SEG8 
PRESS-FIT 
ORIENTATION KEY 
J7 
CONN44_10117936003LF 
S3 S3 
S4 S4 
S5 S5 
S6 S6 
S12 S12 
S11 S11 
S10 S10 
S9 S9 
S8 S8 
S7 S7 
P16 P16 P15 P15 P14 P14 P13 P13 
P1 P1 
P2 P2 
P3 P3 
P12 P12 P11 P11 P10 P10 P9 P9 
P5 P5 
P6 P6 
P7 P7 
P8 P8 
S2 S2 S1 S1 
P4 P4 
P17 P17 P18 P18 P19 P19 P20 P20 
P21 P21 P22 P22 P23 P23 P24 P24 
P25 P25 P26 P26 P27 P27 P28 P28 
P29 P29 P30 P30 P31 P31 P32 P32 
Signal 
SEG1 
SEG2 
SEG3 
SEG4 SEG5 
SEG6 
SEG7 
SEG8 
PRESS-FIT 
ORIENTATION KEY 
J11 
CONN44_10117936003LF 
S3 S3 
S4 S4 
S5 S5 
S6 S6 
S12 S12 
S11 S11 
S10 S10 
S9 S9 
S8 S8 
S7 S7 
P16 P16 P15 P15 P14 P14 P13 P13 
P1 P1 
P2 P2 
P3 P3 
P12 P12 P11 P11 P10 P10 P9 P9 
P5 P5 
P6 P6 
P7 P7 
P8 P8 
S2 S2 S1 S1 
P4 P4 
P17 P17 P18 P18 P19 P19 P20 P20 
P21 P21 P22 P22 P23 P23 P24 P24 
P25 P25 P26 P26 P27 P27 P28 P28 
P29 P29 P30 P30 P31 P31 P32 P32 
C4 
0.1UF 
25V 
C0402 
+ CE9 
470UF 
16V 
1 2
C15 
1UF 
25V 
C0603 
+ CE2 
470UF 
16V 
1 2
Signal 
SEG1 
SEG2 
SEG3 
SEG4 SEG5 
SEG6 
SEG7 
SEG8 
PRESS-FIT 
ORIENTATION KEY 
J8 
CONN44_10117936003LF 
S3 S3 
S4 S4 
S5 S5 
S6 S6 
S12 S12 
S11 S11 
S10 S10 
S9 S9 
S8 S8 
S7 S7 
P16 P16 P15 P15 P14 P14 P13 P13 
P1 P1 
P2 P2 
P3 P3 
P12 P12 P11 P11 P10 P10 P9 P9 
P5 P5 
P6 P6 
P7 P7 
P8 P8 
S2 S2 S1 S1 
P4 P4 
P17 P17 P18 P18 P19 P19 P20 P20 
P21 P21 P22 P22 P23 P23 P24 P24 
P25 P25 P26 P26 P27 P27 P28 P28 
P29 P29 P30 P30 P31 P31 P32 P32 
C28 
100PF
50V 
C0402
+ CE3 
470UF 
16V 
1 2
C17 
0.1UF 
25V 
C0402 
C41 
0.1UF 
25V 
C0402 
C12 
0.1UF 
25V 
C0402 
+ CE12 
470UF 
16V 
1 2
C20 
0.1UF 
25V 
C0402 
C37 
0.1UF 
25V 
C0402 
C13 
0.1UF 
25V 
C0402 
+ CE7 
470UF 
16V 
1 2
C29 
1UF 
25V 
C0603 
+ CE10 
470UF 
16V 
1 2
C36 
1UF 
25V 
C0603 
C11 
0.1UF 
25V 
C0402 
C5 
0.1UF 
25V 
C0402 
Signal 
SEG1 
SEG2 
SEG3 
SEG4 SEG5 
SEG6 
SEG7 
SEG8 
PRESS-FIT 
ORIENTATION KEY 
J10 
CONN44_10117936003LF 
S3 S3 
S4 S4 
S5 S5 
S6 S6 
S12 S12 
S11 S11 
S10 S10 
S9 S9 
S8 S8 
S7 S7 
P16 P16 P15 P15 P14 P14 P13 P13 
P1 P1 
P2 P2 
P3 P3 
P12 P12 P11 P11 P10 P10 P9 P9 
P5 P5 
P6 P6 
P7 P7 
P8 P8 
S2 S2 S1 S1 
P4 P4 
P17 P17 P18 P18 P19 P19 P20 P20 
P21 P21 P22 P22 P23 P23 P24 P24 
P25 P25 P26 P26 P27 P27 P28 P28 
P29 P29 P30 P30 P31 P31 P32 P32 
C40 
0.1UF 
25V 
C0402 
+ CE8 
470UF 
16V 
1 2
C24 
0.1UF 
25V 
C0402 
C3 
0.1UF 
25V 
C0402 
C25 
0.1UF 
25V 
C0402 
C42 
100PF 
50V 
C0402 
+ CE4 
470UF 
16V 
1 2
C1 
1UF 
25V 
C0603 
C22 
1UF 
25V 
C0603 
C38 
0.1UF 
25V 
C0402 
C32 
0.1UF 
25V 
C0402 
C7 
100PF 
50V 
C0402 
+ CE6 
470UF 
16V 
1 2
C26 
0.1UF 
25V 
C0402 
C27 
0.1UF 
25V 
C0402 



5
5
4
4
3
3
2
2
1
1
D D
C C
B B
A A
TRAY 7 TRAY 8 TRAY 9 
TRAY 10 TRAY 11 TRAY 12 
FOR TRAY7 FOR TRAY8 FOR TRAY9 FOR TRAY10 
FOR TRAY11 FOR TRAY12 
B13_PSU_ALERT_N 4
T7_BLAD3_TXD 8
T7_BLAD3_EN 8
T7_BLAD4_TXD 8
T7_BLAD1_TXD 8
T7_BLAD1_RXD 8 T7_BLAD3_RXD 8
B14_PSU_ALERT_N 4
T7_BLAD1_EN 8
T7_BLAD2_TXD 8
T7_BLAD2_RXD 8 T7_BLAD4_RXD 8
B15_PSU_ALERT_N 4
T8_BLAD3_TXD 8
T8_BLAD3_EN 8
T8_BLAD4_TXD 8
T8_BLAD3_RXD 8
B16_PSU_ALERT_N 4
T8_BLAD1_TXD 8
T8_BLAD1_RXD 8
T8_BLAD4_RXD 8
T8_BLAD1_EN 8
T8_BLAD2_TXD 8
T8_BLAD2_RXD 8
B17_PSU_ALERT_N 4
T9_BLAD3_TXD 8
T9_BLAD3_EN 8
T9_BLAD4_TXD 8
T9_BLAD3_RXD 8
T9_BLAD1_TXD 8
T9_BLAD1_RXD 8
B18_PSU_ALERT_N 4
T9_BLAD4_RXD 8
T9_BLAD1_EN 8
T9_BLAD2_TXD 8
T9_BLAD2_RXD 8
T10_BLAD3_TXD 8
T10_BLAD3_EN 8
B19_PSU_ALERT_N 4
T10_BLAD4_TXD 8
T10_BLAD3_RXD 8
B20_PSU_ALERT_N 4
T10_BLAD4_RXD 8
T10_BLAD1_TXD 8
T10_BLAD1_RXD 8
T10_BLAD1_EN 8
T10_BLAD2_TXD 8
T10_BLAD2_RXD 8
B21_PSU_ALERT_N 4
T11_BLAD3_TXD 8
T11_BLAD3_EN 8
T11_BLAD4_TXD 8
T11_BLAD3_RXD 8
B22_PSU_ALERT_N 4
T11_BLAD1_TXD 8
T11_BLAD1_RXD 8
T11_BLAD4_RXD 8
T11_BLAD1_EN 8
T11_BLAD2_TXD 8
T11_BLAD2_RXD 8
B23_PSU_ALERT_N 4
T12_BLAD3_TXD 8
T12_BLAD3_EN 8
T12_BLAD4_TXD 8
T12_BLAD3_RXD 8
B24_PSU_ALERT_N 4
T12_BLAD1_TXD 8
T12_BLAD1_RXD 8
T12_BLAD1_EN 8
T12_BLAD4_RXD 8
T12_BLAD2_TXD 8
T12_BLAD2_RXD 8
P12V P12V 
P12V 
P12V P12V P12V 
P12V P12V P12V P12V 
P12V P12V 
P12V P12V P12V P12V 
P12V P12V P12V 
Title 
Size Document Number Rev
Date: Sheet 
of 
N/A 1A
Power Distribution Backplane V2 
Microsoft Corporation 
C
7 11Monday, November 24, 2014 
Title 
Size Document Number Rev
Date: Sheet 
of 
N/A 1A
Power Distribution Backplane V2 
Microsoft Corporation 
C
7 11Monday, November 24, 2014 
Title 
Size Document Number Rev
Date: Sheet 
of 
N/A 1A
Power Distribution Backplane V2 
Microsoft Corporation 
C
7 11Monday, November 24, 2014 
C69 
0.1UF 
25V 
C0402 
C46 
0.1UF 
25V 
C0402 
+ CE17 
470UF 
16V 
1 2
C62 
0.1UF 
25V 
C0402 
C82 
0.1UF 
25V 
C0402 
C66 
0.1UF 
25V 
C0402 
C48 
0.1UF 
25V 
C0402 
+ CE18 
470UF 
16V 
1 2
Signal 
SEG1 
SEG2 
SEG3 
SEG4 SEG5 
SEG6 
SEG7 
SEG8 
PRESS-FIT 
ORIENTATION KEY 
J13 
CONN44_10117936003LF 
S3 S3 
S4 S4 
S5 S5 
S6 S6 
S12 S12 
S11 S11 
S10 S10 
S9 S9 
S8 S8 
S7 S7 
P16 P16 P15 P15 P14 P14 P13 P13 
P1 P1 
P2 P2 
P3 P3 
P12 P12 P11 P11 P10 P10 P9 P9 
P5 P5 
P6 P6 
P7 P7 
P8 P8 
S2 S2 S1 S1 
P4 P4 
P17 P17 P18 P18 P19 P19 P20 P20 
P21 P21 P22 P22 P23 P23 P24 P24 
P25 P25 P26 P26 P27 P27 P28 P28 
P29 P29 P30 P30 P31 P31 P32 P32 
Signal 
SEG1 
SEG2 
SEG3 
SEG4 SEG5 
SEG6 
SEG7 
SEG8 
PRESS-FIT 
ORIENTATION KEY 
J17 
CONN44_10117936003LF 
S3 S3 
S4 S4 
S5 S5 
S6 S6 
S12 S12 
S11 S11 
S10 S10 
S9 S9 
S8 S8 
S7 S7 
P16 P16 P15 P15 P14 P14 P13 P13 
P1 P1 
P2 P2 
P3 P3 
P12 P12 P11 P11 P10 P10 P9 P9 
P5 P5 
P6 P6 
P7 P7 
P8 P8 
S2 S2 S1 S1 
P4 P4 
P17 P17 P18 P18 P19 P19 P20 P20 
P21 P21 P22 P22 P23 P23 P24 P24 
P25 P25 P26 P26 P27 P27 P28 P28 
P29 P29 P30 P30 P31 P31 P32 P32 
C59 
0.1UF 
25V 
C0402 
C74 
0.1UF 
25V 
C0402 
C78 
1UF 
25V 
C0603 
+ CE15 
470UF 
16V 
1 2
C65 
0.1UF 
25V 
C0402 
C45 
0.1UF 
25V 
C0402 
C58 
0.1UF 
25V 
C0402 
C76 
0.1UF 
25V 
C0402 
C84 
100PF 
50V 
C0402 
+ CE16 
470UF 
16V 
1 2
C53 
0.1UF 
25V 
C0402 
Signal 
SEG1 
SEG2 
SEG3 
SEG4 SEG5 
SEG6 
SEG7 
SEG8 
PRESS-FIT 
ORIENTATION KEY 
J14 
CONN44_10117936003LF 
S3 S3 
S4 S4 
S5 S5 
S6 S6 
S12 S12 
S11 S11 
S10 S10 
S9 S9 
S8 S8 
S7 S7 
P16 P16 P15 P15 P14 P14 P13 P13 
P1 P1 
P2 P2 
P3 P3 
P12 P12 P11 P11 P10 P10 P9 P9 
P5 P5 
P6 P6 
P7 P7 
P8 P8 
S2 S2 S1 S1 
P4 P4 
P17 P17 P18 P18 P19 P19 P20 P20 
P21 P21 P22 P22 P23 P23 P24 P24 
P25 P25 P26 P26 P27 P27 P28 P28 
P29 P29 P30 P30 P31 P31 P32 P32 
C44 
0.1UF 
25V 
C0402 
+ CE19 
470UF 
16V 
1 2
C68 
0.1UF 
25V 
C0402 
C73 
0.1UF 
25V 
C0402 
C61 
0.1UF 
25V 
C0402 
+ CE21 
470UF 
16V 
1 2
C55 
0.1UF 
25V 
C0402 
+ CE20 
470UF 
16V 
1 2
C64 
1UF 
25V 
C0603 
C47 
0.1UF 
25V 
C0402 
+ CE13 
470UF 
16V 
1 2
C57 
1UF 
25V 
C0603 
C72 
0.1UF 
25V 
C0402 
C52 
0.1UF 
25V 
C0402 
C70 
100PF
50V 
C0402
C43 
1UF 
25V 
C0603 
Signal 
SEG1 
SEG2 
SEG3 
SEG4 SEG5 
SEG6 
SEG7 
SEG8 
PRESS-FIT 
ORIENTATION KEY 
J16 
CONN44_10117936003LF 
S3 S3 
S4 S4 
S5 S5 
S6 S6 
S12 S12 
S11 S11 
S10 S10 
S9 S9 
S8 S8 
S7 S7 
P16 P16 P15 P15 P14 P14 P13 P13 
P1 P1 
P2 P2 
P3 P3 
P12 P12 P11 P11 P10 P10 P9 P9 
P5 P5 
P6 P6 
P7 P7 
P8 P8 
S2 S2 S1 S1 
P4 P4 
P17 P17 P18 P18 P19 P19 P20 P20 
P21 P21 P22 P22 P23 P23 P24 P24 
P25 P25 P26 P26 P27 P27 P28 P28 
P29 P29 P30 P30 P31 P31 P32 P32 
C75 
0.1UF 
25V 
C0402 
+ CE22 
470UF 
16V 
1 2
C63 
100PF 
50V 
C0402 
C51 
0.1UF 
25V 
C0402 
C49 
100PF 
50V 
C0402 
+ CE23 
470UF 
16V 
1 2
C71 
1UF 
25V 
C0603 
C81 
0.1UF 
25V 
C0402 
C54 
0.1UF 
25V 
C0402 
+ CE14 
470UF 
16V 
1 2
+ CE24 
470UF 
16V 
1 2
C77 
100PF 
50V 
C0402 
Signal 
SEG1 
SEG2 
SEG3 
SEG4 SEG5 
SEG6 
SEG7 
SEG8 
PRESS-FIT 
ORIENTATION KEY 
J18 
CONN44_10117936003LF 
S3 S3 
S4 S4 
S5 S5 
S6 S6 
S12 S12 
S11 S11 
S10 S10 
S9 S9 
S8 S8 
S7 S7 
P16 P16 P15 P15 P14 P14 P13 P13 
P1 P1 
P2 P2 
P3 P3 
P12 P12 P11 P11 P10 P10 P9 P9 
P5 P5 
P6 P6 
P7 P7 
P8 P8 
S2 S2 S1 S1 
P4 P4 
P17 P17 P18 P18 P19 P19 P20 P20 
P21 P21 P22 P22 P23 P23 P24 P24 
P25 P25 P26 P26 P27 P27 P28 P28 
P29 P29 P30 P30 P31 P31 P32 P32 
C83 
0.1UF 
25V 
C0402 
C50 
1UF 
25V 
C0603 
C80 
0.1UF 
25V 
C0402 
C56 
100PF 
50V 
C0402 
Signal 
SEG1 
SEG2 
SEG3 
SEG4 SEG5 
SEG6 
SEG7 
SEG8 
PRESS-FIT 
ORIENTATION KEY 
J15 
CONN44_10117936003LF 
S3 S3 
S4 S4 
S5 S5 
S6 S6 
S12 S12 
S11 S11 
S10 S10 
S9 S9 
S8 S8 
S7 S7 
P16 P16 P15 P15 P14 P14 P13 P13 
P1 P1 
P2 P2 
P3 P3 
P12 P12 P11 P11 P10 P10 P9 P9 
P5 P5 
P6 P6 
P7 P7 
P8 P8 
S2 S2 S1 S1 
P4 P4 
P17 P17 P18 P18 P19 P19 P20 P20 
P21 P21 P22 P22 P23 P23 P24 P24 
P25 P25 P26 P26 P27 P27 P28 P28 
P29 P29 P30 P30 P31 P31 P32 P32 
C67 
0.1UF 
25V 
C0402 
C60 
0.1UF 
25V 
C0402 
C79 
0.1UF 
25V 
C0402 



5
5
4
4
3
3
2
2
1
1
D D
C C
B B
A A
MATE_A1 
POWER_SW3_PWR_CTR_12V 
POWER_SW2_PWR_CTR_12V 
POWER_SW1_PWR_CTR_12V 
TP_T11_BLAD2_EN 
TP_T11_BLAD4_EN 
TP_T9_BLAD4_EN 
TP_T9_BLAD2_EN 
TP_T7_BLAD2_EN 
TP_T7_BLAD4_EN 
TP_T5_BLAD2_EN 
TP_T5_BLAD4_EN 
TP_T12_BLAD2_EN 
TP_T12_BLAD4_EN 
TP_T10_BLAD2_EN 
TP_T10_BLAD4_EN 
TP_T8_BLAD2_EN 
TP_T8_BLAD4_EN 
TP_T6_BLAD4_EN 
TP_T6_BLAD2_EN 
CM_PWR_CTL_IN 
MATE_A1 
POWER_SW3_PWR_CTR_12V 
POWER_SW2_PWR_CTR_12V 
POWER_SW1_PWR_CTR_12V 
CM_PWR_CTL_IN 
TP_T3_BLAD2_EN 
TP_T3_BLAD4_EN 
T1_BLAD2_EN 
TP_T1_BLAD4_EN 
TP_T4_BLAD2_EN 
TP_T4_BLAD4_EN 
TP_T2_BLAD2_EN 
TP_T2_BLAD4_EN 
PSU_ALERT_N 
LAN2_P3_P 10 
LAN2_P3_N 10 
LAN2_P4_P 10 
LAN2_P4_N 10 
FAN4_TACH 9
FAN5_TACH 9
FAN6_TACH 9
FAN_PWM 9
T11_BLAD1_EN 7
T11_BLAD3_EN 7
I2C_PSU3_SDA 5
I2C_PSU3_SCL 5
T11_BLAD1_TXD 7
T11_BLAD1_RXD 7
T11_BLAD2_TXD 7
T11_BLAD2_RXD 7
T11_BLAD3_TXD 7
T11_BLAD3_RXD 7
T11_BLAD4_RXD 7
T11_BLAD4_TXD 7
T9_BLAD3_EN 7
T9_BLAD1_EN 7
T9_BLAD1_TXD 7
T9_BLAD1_RXD 7
T9_BLAD2_TXD 7
T9_BLAD2_RXD 7
T9_BLAD3_RXD 7
T9_BLAD3_TXD 7
T9_BLAD4_RXD 7
T9_BLAD4_TXD 7
T7_BLAD1_EN 7
T7_BLAD3_EN 7
T7_BLAD2_RXD 7
T7_BLAD2_TXD 7
T7_BLAD1_RXD 7
T7_BLAD1_TXD 7
T7_BLAD3_TXD 7
T7_BLAD3_RXD 7
T7_BLAD4_RXD 7
T7_BLAD4_TXD 7
PSU_ALERT_N 4,5,8 
T5_BLAD1_EN 6
T5_BLAD3_EN 6
T5_BLAD1_RXD 6
T5_BLAD1_TXD 6
T5_BLAD2_RXD 6
T5_BLAD2_TXD 6
T5_BLAD3_RXD 6
T5_BLAD3_TXD 6
LAN1_P1_P 10 
LAN1_P1_N 10 
LAN1_P2_P 10 
LAN1_P2_N 10 
LAN2_P1_P 10 
LAN2_P1_N 10 
LAN2_P2_P 10 
LAN2_P2_N 10 
I2C_PDB_SCL 9
I2C_PDB_SDA 9
FAN1_TACH 9
FAN2_TACH 9
FAN3_TACH 9
T12_BLAD1_EN 7
T12_BLAD3_EN 7
T12_BLAD1_TXD 7
T12_BLAD1_RXD 7
T12_BLAD2_TXD 7
T12_BLAD2_RXD 7
T12_BLAD3_RXD 7
T12_BLAD3_TXD 7
T12_BLAD4_RXD 7
T12_BLAD4_TXD 7
T10_BLAD1_EN 7
T10_BLAD3_EN 7
T10_BLAD1_TXD 7
T10_BLAD1_RXD 7
T10_BLAD2_TXD 7
T10_BLAD2_RXD 7
T10_BLAD3_RXD 7
T10_BLAD3_TXD 7
T10_BLAD4_RXD 7
T10_BLAD4_TXD 7
T8_BLAD1_EN 7
T8_BLAD3_EN 7
T8_BLAD1_RXD 7
T8_BLAD1_TXD 7
T8_BLAD2_RXD 7
T8_BLAD2_TXD 7
T8_BLAD3_RXD 7
T8_BLAD3_TXD 7
T8_BLAD4_RXD 7
T8_BLAD4_TXD 7
T6_BLAD1_EN 6
T6_BLAD3_EN 6
T6_BLAD1_RXD 6
T6_BLAD1_TXD 6
T6_BLAD2_RXD 6
T6_BLAD2_TXD 6
T6_BLAD3_RXD 6
T6_BLAD3_TXD 6
T6_BLAD4_RXD 6
T6_BLAD4_TXD 6
I2C_PSU2_SCL 5
I2C_PSU2_SDA 5
LAN1_P3_P 10 
LAN1_P3_N 10 
LAN1_P4_P 10 
LAN1_P4_N 10 
PSU1_PS_ON_N 5
PSU2_PS_ON_N 5
PSU3_PS_ON_N 5
PSU4_PS_ON_N 5
PSU5_PS_ON_N 5
PSU6_PS_ON_N 5
T5_BLAD4_RXD 6
T5_BLAD4_TXD 6
T3_BLAD1_EN 6
T3_BLAD3_EN 6
T3_BLAD1_RXD 6
T3_BLAD1_TXD 6
T3_BLAD2_RXD 6
T3_BLAD2_TXD 6
T3_BLAD3_RXD 6
T3_BLAD3_TXD 6
T3_BLAD4_RXD 6
T3_BLAD4_TXD 6
T1_BLAD1_EN 6
T1_BLAD3_EN 6
PSU1_DC_OK 5
PSU2_DC_OK 5
PSU3_DC_OK 5
PSU4_DC_OK 5
PSU5_DC_OK 5
PSU6_DC_OK 5
T4_BLAD1_EN 6
T4_BLAD3_EN 6
T4_BLAD1_RXD 6
T4_BLAD1_TXD 6
T4_BLAD2_RXD 6
T4_BLAD2_TXD 6
T4_BLAD3_RXD 6
T4_BLAD3_TXD 6
T4_BLAD4_RXD 6
T4_BLAD4_TXD 6
T2_BLAD3_EN 6
T2_BLAD1_EN 6
T2_BLAD1_RXD 6
T2_BLAD1_TXD 6
T2_BLAD2_RXD 6
T2_BLAD2_TXD 6
T2_BLAD3_RXD 6
T2_BLAD3_TXD 6
T2_BLAD4_RXD 6
T2_BLAD4_TXD 6
I2C_PSU1_SCL 5
I2C_PSU1_SDA 5
PSU1_AC_OK 5
PSU2_AC_OK 5
PSU3_AC_OK 5
PSU4_AC_OK 5
PSU5_AC_OK 5
PSU6_AC_OK 5
UART_RTS_P5_L_N 10 
UART_TX_P5_L 10 
UART_CTS_P5_L_N 10 
UART_DSR_P5_L_N 10 
UART_RX_P5_L 10 
UART_DTR_P5_L_N 10 
UART_RI_P5_L_N 10 
UART_TX_P1_L 10 
UART_CTS_P1_L_N 10 
UART_RX_P1_L 10 
UART_DTR_P1_L_N 10 
UART_RTS_P1_L_N 10 
UART_DSR_P1_L_N 10 
UART_RI_P6_L_N 10 
UART_RTS_P6_L_N 10 
UART_DSR_P6_L_N 10 
UART_RX_P6_L 10 
UART_DTR_P6_L_N 10 
UART_TX_P6_L 10 
UART_CTS_P6_L_N 10 
UART_DSR_P2_L_N 10 
UART_RX_P2_L 10 
UART_DTR_P2_L_N 10 
UART_TX_P2_L 10 
UART_CTS_P2_L_N 10 
UART_RTS_P2_L_N 10 
T1_BLAD1_RXD 6
T1_BLAD1_TXD 6
T1_BLAD2_RXD 6
T1_BLAD2_TXD 6
T1_BLAD3_RXD 6
T1_BLAD3_TXD 6
T1_BLAD4_RXD 6
T1_BLAD4_TXD 6
PSU_ALERT_N 4,5,8
P12V 
P3V3 
P12V 
Title 
Size Document Number Rev
Date: Sheet 
of 
N/A 1A
Power Distribution Backplane V2 
Microsoft Corporation 
C
8 11Monday, November 24, 2014 
Title 
Size Document Number Rev
Date: Sheet 
of 
N/A 1A
Power Distribution Backplane V2 
Microsoft Corporation 
C
8 11Monday, November 24, 2014 
Title 
Size Document Number Rev
Date: Sheet 
of 
N/A 1A
Power Distribution Backplane V2 
Microsoft Corporation 
C
8 11Monday, November 24, 2014 
R163 0
R0402 1% 
J31 
CONN2_43650-0217 
1 1
2 2
R49 560 
R53 560 
J32 
CONN2_43650-0217 
1 1
2 2
R54 560 
J33 
CONN2_43650-0217 
1 1
2 2
KEY
J26 
PCIEX16 
12V_1 B1 
12V_2 B2 
12V_3 B3 
GND1 B4 
SMCLK B5 
SMDATA B6 
GND2 B7 
3.3V_1 B8 
JTAG1 B9 
3.3VAUX B10 
WAKE_N B11 
RSVD1 B12 
GND3 B13 
HSOP0+ B14 
HSOP0- B15 
GND4 B16 
PRSNT2_N-1 B17 
GND5 B18 
HSOP1+ B19 
HSOP1- B20 
GND6 B21 
GND7 B22 
HSOP2+ B23 
HSOP2- B24 
GND8 B25 
GND9 B26 
HSOP3+ B27 
HSOP3- B28 
GND10 B29 
RSVD2 B30 
PRSNT2_N-2 B31 
GND11 B32 
HSOP4+ B33 
HSOP4- B34 
GND12 B35 
GND13 B36 
HSOP5+ B37 
HSOP5- B38 
GND14 B39 
GND15 B40 
HSOP6+ B41 
HSOP6- B42 
GND16 B43 
GND17 B44 
HSOP7+ B45 
HSOP7- B46 
GND18 B47 
PRSNT2_N-3 B48 
GND19 B49 
PRSNT1_N A1 
12V_4 A2 
12V_5 A3 
GND35 A4 
JTAG2 A5 
JTAG3 A6 
JTAG4 A7 
JTAG5 A8 
3.3V_2 A9 
3.3V_3 A10 
PERST# A11 
GND36 A12 
REFCLK+ A13 
REFCLK- A14 
GND37 A15 
HSIP0+ A16 
HSIP0- A17 
GND38 A18 
RSVD4 A19 
GND39 A20 
HSIP1+ A21 
HSIP1- A22 
GND40 A23 
GND41 A24 
HSIP2+ A25 
HSIP2- A26 
GND42 A27 
GND43 A28 
HSIP3+ A29 
HSIP3- A30 
GND44 A31 
RSVD5 A32 
RSVD6 A33 
GND45 A34 
HSIP4+ A35 
HSIP4- A36 
GND46 A37 
GND47 A38 
HSIP5+ A39 
HSIP5- A40 
GND48 A41 
GND49 A42 
HSIP6+ A43 
HSIP6- A44 
GND50 A45 
GND51 A46 
HSIP7+ A47 
HSIP7- A48 
GND52 A49 
RSVD7 A50 
GND53 A51 
HSIP8+ A52 
HSIP8- A53 
GND54 A54 
GND55 A55 
HSIP9+ A56 
HSIP9- A57 
GND56 A58 
GND57 A59 
HSIP10+ A60 
HSIP10- A61 
GND58 A62 
GND59 A63 
HSIP11+ A64 
HSIP11- A65 
GND60 A66 
RSVD8 A67 
HSIP12+ A68 
HSIP12- A69 
GND61 A70 
GND62 A71 
HSIP13+ A72 
HSIP13- A73 
GND63 A74 
GND64 A75 
HSIP14 A76 
HSIP14- A77 
GND65 A78 
GND66 A79 
HSIP15+ A80 
HSIP15- A81 
GND67 A82 
HSOP8+ B50 
HSOP8- B51 
GND20 B52 
GND21 B53 
HSOP9+ B54 
HSOP9- B55 
GND22 B56 
GND23 B57 
HSOP10+ B58 
HSOP10- B59 
GND24 B60 
GND25 B61 
HSOP11+ B62 
HSOP11- B63 
GND26 B64 
GND27 B65 
HSOP12+ B66 
HSOP12- B67 
GND28 B68 
GND29 B69 
HSOP13+ B70 
HSOP13- B71 
GND30 B72 
GND31 B73 
HSOP14+ B74 
HSOP14- B75 
GND32 B76 
GND33 B77 
HSOP15+ B78 
HSOP15- B79 
GND34 B80 
PRSNT2_N-4 B81 
RSVD3 B82 
R50 560 
KEY
J25 
PCIEX16 
12V_1 B1 
12V_2 B2 
12V_3 B3 
GND1 B4 
SMCLK B5 
SMDATA B6 
GND2 B7 
3.3V_1 B8 
JTAG1 B9 
3.3VAUX B10 
WAKE_N B11 
RSVD1 B12 
GND3 B13 
HSOP0+ B14 
HSOP0- B15 
GND4 B16 
PRSNT2_N-1 B17 
GND5 B18 
HSOP1+ B19 
HSOP1- B20 
GND6 B21 
GND7 B22 
HSOP2+ B23 
HSOP2- B24 
GND8 B25 
GND9 B26 
HSOP3+ B27 
HSOP3- B28 
GND10 B29 
RSVD2 B30 
PRSNT2_N-2 B31 
GND11 B32 
HSOP4+ B33 
HSOP4- B34 
GND12 B35 
GND13 B36 
HSOP5+ B37 
HSOP5- B38 
GND14 B39 
GND15 B40 
HSOP6+ B41 
HSOP6- B42 
GND16 B43 
GND17 B44 
HSOP7+ B45 
HSOP7- B46 
GND18 B47 
PRSNT2_N-3 B48 
GND19 B49 
PRSNT1_N A1 
12V_4 A2 
12V_5 A3 
GND35 A4 
JTAG2 A5 
JTAG3 A6 
JTAG4 A7 
JTAG5 A8 
3.3V_2 A9 
3.3V_3 A10 
PERST# A11 
GND36 A12 
REFCLK+ A13 
REFCLK- A14 
GND37 A15 
HSIP0+ A16 
HSIP0- A17 
GND38 A18 
RSVD4 A19 
GND39 A20 
HSIP1+ A21 
HSIP1- A22 
GND40 A23 
GND41 A24 
HSIP2+ A25 
HSIP2- A26 
GND42 A27 
GND43 A28 
HSIP3+ A29 
HSIP3- A30 
GND44 A31 
RSVD5 A32 
RSVD6 A33 
GND45 A34 
HSIP4+ A35 
HSIP4- A36 
GND46 A37 
GND47 A38 
HSIP5+ A39 
HSIP5- A40 
GND48 A41 
GND49 A42 
HSIP6+ A43 
HSIP6- A44 
GND50 A45 
GND51 A46 
HSIP7+ A47 
HSIP7- A48 
GND52 A49 
RSVD7 A50 
GND53 A51 
HSIP8+ A52 
HSIP8- A53 
GND54 A54 
GND55 A55 
HSIP9+ A56 
HSIP9- A57 
GND56 A58 
GND57 A59 
HSIP10+ A60 
HSIP10- A61 
GND58 A62 
GND59 A63 
HSIP11+ A64 
HSIP11- A65 
GND60 A66 
RSVD8 A67 
HSIP12+ A68 
HSIP12- A69 
GND61 A70 
GND62 A71 
HSIP13+ A72 
HSIP13- A73 
GND63 A74 
GND64 A75 
HSIP14 A76 
HSIP14- A77 
GND65 A78 
GND66 A79 
HSIP15+ A80 
HSIP15- A81 
GND67 A82 
HSOP8+ B50 
HSOP8- B51 
GND20 B52 
GND21 B53 
HSOP9+ B54 
HSOP9- B55 
GND22 B56 
GND23 B57 
HSOP10+ B58 
HSOP10- B59 
GND24 B60 
GND25 B61 
HSOP11+ B62 
HSOP11- B63 
GND26 B64 
GND27 B65 
HSOP12+ B66 
HSOP12- B67 
GND28 B68 
GND29 B69 
HSOP13+ B70 
HSOP13- B71 
GND30 B72 
GND31 B73 
HSOP14+ B74 
HSOP14- B75 
GND32 B76 
GND33 B77 
HSOP15+ B78 
HSOP15- B79 
GND34 B80 
PRSNT2_N-4 B81 
RSVD3 B82 
R51 560 
R52 560 
J30 
CONN2_43650-0217 
1 1
2 2



5
5
4
4
3
3
2
2
1
1
D D
C C
B B
A A
RATED CURRENT 4.0 ( 5.2MAX.) Amp. 
RATED POWER     48 ( 62.4MAX.) Watt. 
FAN 1 ~ 6 
remeber to change correct molex connector 
ADDRESS = A2 
RESERVE 
I2C PU @ CM
Note:  Resistors R681 and R683 need to be populated on the CM
 in order for this EEPROM to work.
Both of these resistors are currently "NI".
Add 12V power connector : 43650-0317 
FAN_PWM FAN1_TACH 
FAN2_TACH 
FAN3_TACH 
FAN4_TACH 
FAN5_TACH 
FAN6_TACH 
FRU_WP 
FRU_A0 
FRU_A1 
FRU_A2 
FRU_WP 
FRU_A0 FRU_A1 FRU_A2 
FAN5_TACH 8
FAN6_TACH 8
FAN1_TACH 8
FAN2_TACH 8
FAN3_TACH 8
FAN4_TACH 8
FAN_PWM 8
I2C_PDB_SCL 8
I2C_PDB_SDA 8
P12V P12V 
P12V 
P3V3 
P3V3 
P3V3 
P3V3 P3V3 
P12V 
P12V P3V3_BUF 
Title 
Size Document Number Rev
Date: Sheet 
of 
N/A 1A
Power Distribution Backplane V2 
Microsoft Corporation 
C
9 11Monday, November 24, 2014 
Title 
Size Document Number Rev
Date: Sheet 
of 
N/A 1A
Power Distribution Backplane V2 
Microsoft Corporation 
C
9 11Monday, November 24, 2014 
Title 
Size Document Number Rev
Date: Sheet 
of 
N/A 1A
Power Distribution Backplane V2 
Microsoft Corporation 
C
9 11Monday, November 24, 2014 
R36 3.3K 
5% R0402 
NI 
C87 
10UF C0805_H61 
10% 
25V 
C88 
10UF 
C0805_H61 
10% 
25V 
R156 
30.1K 
1% 
R0402 
U1 
M24128-BWMN6TP 
VCC 8
WC 7
SCL 6
SDA 5 VSS 4E2 3E1 2E0 1
C89 
10UF 
C0805_H61 
10% 
25V 
R38 100 
R157 
18.2K 
1% 
R0402 
R41 10K 
5% R0402 
CS31002JB28 
NI 
C90 
0.1UF C0402 
10% 
25V J20 
CONN20_39281203 
11
22
33
44
55
66
77
88
99
10 10 
11 11 
12 12 
13 13 
14 14 
15 15 
16 16 
17 17 
18 18 
19 19 
20 20 
C91 
0.1UF 
C0402 
10% 
25V 
R154 
0
1% 
R0402 
R144 8.2K 
5% R0402 
R155 
0
1% 
R0402 
R39 100 
U2 
MIC39102YM 
GND 8
GND 7
IN 2
ADJ 4OUT 3
GND 6
EN 1
GND 5
R145 8.2K 
5% R0402 
R143 8.2K 
5% R0402 
R140 8.2K 
5% R0402 
R146 8.2K 
5% R0402 
R141 22.1K 
1% R0402 
R147 8.2K 
5% R0402 
R142 8.2K 
5% R0402 
R34 3.3K 
5% R0402 
C85 
10UF C0805_H61 
10% 
25V 
R35 3.3K 
5% R0402 
NI 
J34 
CONN3_43650-0317 
1 1
2 2
3 3
R37 100 NI 
C86 
10UF C0805_H61 
10% 
25V 



5
5
4
4
3
3
2
2
1
1
D D
C C
B B
A A
LAN2_P1_N 8
LAN2_P1_P 8
LAN2_P4_N 8
LAN2_P4_P 8
LAN2_P2_P 8
LAN1_P2_P 8
LAN1_P1_N 8
LAN1_P1_P 8
LAN1_P4_N 8
LAN1_P4_P 8
UART_RTS_P1_L_N 8
UART_DSR_P1_L_N 8
UART_RX_P1_L 8
UART_TX_P1_L 8
UART_DTR_P1_L_N 8
UART_CTS_P1_L_N 8
UART_RTS_P2_L_N 8
UART_DSR_P2_L_N 8
UART_RX_P2_L 8
UART_TX_P2_L 8
UART_DTR_P2_L_N 8
UART_CTS_P2_L_N 8
UART_RTS_P5_L_N 8
UART_DSR_P5_L_N 8
UART_RI_P5_L_N 8
UART_RX_P5_L 8
UART_TX_P5_L 8
UART_CTS_P5_L_N 8
UART_DTR_P5_L_N 8
UART_RTS_P6_L_N 8
UART_DSR_P6_L_N 8
UART_RI_P6_L_N 8
UART_RX_P6_L 8
UART_TX_P6_L 8
UART_CTS_P6_L_N 8
UART_DTR_P6_L_N 8
LAN2_P2_N 8
LAN2_P3_N 8
LAN2_P3_P 8
LAN1_P3_N 8
LAN1_P2_N 8
LAN1_P3_P 8
Title 
Size Document Number Rev
Date: Sheet 
of 
N/A 1A
Power Distribution Backplane V2 
Microsoft Corporation 
C
10 11Monday, November 24, 2014 
Title 
Size Document Number Rev
Date: Sheet 
of 
N/A 1A
Power Distribution Backplane V2 
Microsoft Corporation 
C
10 11Monday, November 24, 2014 
Title 
Size Document Number Rev
Date: Sheet 
of 
N/A 1A
Power Distribution Backplane V2 
Microsoft Corporation 
C
10 11Monday, November 24, 2014 
R150 100 
12345678
J23 
CONN8_55692841 
1
2
3
4
5
6
7
8
12345678
J27 
CONN8_55692841 
1
2
3
4
5
6
7
8
R148 100 
12345678
910 
Orange 
Green 
11 12 
Green 
J29 
CONN12_G71B0250100EU 
9
10 
1
2
3
4
5
6
7
8
12 
11 
G1 
G2 
12345678
J21 
CONN8_55692841 
1
2
3
4
5
6
7
812345678
J19 
CONN8_55692841 
1
2
3
4
5
6
7
8
R151 100 
R152 100 
R153 100 
12345678
910 
Orange 
Green 
11 12 
Green 
J28 
CONN12_G71B0250100EU 
9
10 
1
2
3
4
5
6
7
8
12 
11 
G1 
G2 
R149 100 



5
5
4
4
3
3
2
2
1
1
D D
C C
B B
A A
Title 
Size Document Number Rev
Date: Sheet 
of 
N/A 1A
Power Distribution Backplane V2 
Microsoft Corporation 
C
11 11Monday, November 24, 2014 
Title 
Size Document Number Rev
Date: Sheet 
of 
N/A 1A
Power Distribution Backplane V2 
Microsoft Corporation 
C
11 11Monday, November 24, 2014 
Title 
Size Document Number Rev
Date: Sheet 
of 
N/A 1A
Power Distribution Backplane V2 
Microsoft Corporation 
C
11 11Monday, November 24, 2014 
H3 
GNDHOLE_8PIN 
NI 
H9 
GNDHOLE_8PIN 
NI 
H13 
HOLE_OB5-2X6-2N 
NI 
H15 
D8N 
NI 
H17 
D8N 
NI 
H11 
GNDHOLE_8PIN 
NI 
H18 
D8N 
NI 
H6 
GNDHOLE_8PIN 
NI 
H1 
GNDHOLE_8PIN 
NI 
H5 
GNDHOLE_8PIN 
NI 
H4 
GNDHOLE_8PIN 
NI 
H8 
GNDHOLE_8PIN 
NI 
H12 
GNDHOLE_8PIN 
NI 
H21 
D8N 
NI 
H22 
D8N 
NI 
H14 
HOLE_D5-2N 
NI 
H2 
GNDHOLE_8PIN 
NI 
H16 
D8N 
NI 
H23 
D8N 
NI 
H7 
GNDHOLE_8PIN 
NI 
H10 
GNDHOLE_8PIN 
NI 
H24 
D8N 
NI 
H19 
D8N 
NI 
H25 
D8N 
NI 
H20 
D8N 
NI 
H26 
D8N 
NI 